(kicad_pcb
	(version 20260206)
	(generator "pcbnew")
	(generator_version "10.0")
	(general
		(thickness 1.6)
		(legacy_teardrops no)
	)
	(paper "A4")
	(title_block
		(title "Bryce Canyon_R.DPB_16317-1_OCP.brd")
		(comment 1 "Bryce Canyon / footprints 547-553 of 2099")
	)
	(layers
		(0 "F.Cu" signal "TOP")
		(4 "In1.Cu" signal "L2GND")
		(6 "In2.Cu" signal "L3")
		(8 "In3.Cu" signal "L4VCC")
		(10 "In4.Cu" signal "L5VCC")
		(12 "In5.Cu" signal "L6")
		(14 "In6.Cu" signal "L7GND")
		(2 "B.Cu" signal "BOTTOM")
		(9 "F.Adhes" user "F.Adhesive")
		(11 "B.Adhes" user "B.Adhesive")
		(13 "F.Paste" user "Package Geometry/Pastemask Top")
		(15 "B.Paste" user "Package Geometry/Pastemask Bottom")
		(5 "F.SilkS" user "Ref Des/Silkscreen Top")
		(7 "B.SilkS" user "Ref Des/Silkscreen Bottom")
		(1 "F.Mask" user "Board Geometry/Soldermask Top")
		(3 "B.Mask" user "Board Geometry/Soldermask Bottom")
		(17 "Dwgs.User" user "User.Drawings")
		(19 "Cmts.User" user "User.Comments")
		(21 "Eco1.User" user "User.Eco1")
		(23 "Eco2.User" user "User.Eco2")
		(25 "Edge.Cuts" user "Board Geometry/Outline")
		(27 "Margin" user)
		(31 "F.CrtYd" user "Package Geometry/Place Bound Top")
		(29 "B.CrtYd" user "Package Geometry/Place Bound Bottom")
		(35 "F.Fab" user "Ref Des/Assembly Top")
		(33 "B.Fab" user "Ref Des/Assembly Bottom")
	)
	(footprint ""
		(layer "F.Cu")
		(at 143.129 -132.588 180)
		(property "Reference" "D16"
			(at 0 0 180)
			(layer "F.SilkS")
			(hide yes)
			(effects
				(font
					(size 1.27 1.27)
				)
			)
		)
		(property "Value" "RB551V30-GP"
			(at 0 -6.7818 180)
			(unlocked yes)
			(layer "F.Fab")
			(hide yes)
			(effects
				(font
					(size 1.016 1.016)
					(thickness 0.1524)
				)
			)
		)
		(property "Device Type" "SOD323AKH38"
			(at 0 -8.6868 180)
			(unlocked yes)
			(layer "F.Fab")
			(hide yes)
			(effects
				(font
					(size 1.016 1.016)
					(thickness 0.1524)
				)
			)
		)
		(duplicate_pad_numbers_are_jumpers no)
		(fp_line
			(start 0.889 2.159)
			(end -0.889 2.159)
			(stroke
				(width 0.1524)
				(type default)
			)
			(layer "F.SilkS")
		)
		(fp_line
			(start 0.889 -1.9304)
			(end 0.889 2.159)
			(stroke
				(width 0.1524)
				(type default)
			)
			(layer "F.SilkS")
		)
		(fp_line
			(start 0.762 2.0574)
			(end -0.762 2.0574)
			(stroke
				(width 0.508)
				(type default)
			)
			(layer "F.SilkS")
		)
		(fp_line
			(start -0.889 2.159)
			(end -0.889 -1.9304)
			(stroke
				(width 0.1524)
				(type default)
			)
			(layer "F.SilkS")
		)
		(fp_line
			(start -0.889 -1.9304)
			(end 0.889 -1.9304)
			(stroke
				(width 0.1524)
				(type default)
			)
			(layer "F.SilkS")
		)
		(fp_rect
			(start -1.016 2.3114)
			(end 1.016 -2.0066)
			(stroke
				(width 0)
				(type default)
			)
			(fill no)
			(layer "F.CrtYd")
		)
		(fp_poly
			(pts
				(xy -1.016 -2.0066) (xy 1.016 -2.0066) (xy 1.016 2.3114) (xy -1.016 2.3114)
			)
			(stroke
				(width 0)
				(type default)
			)
			(fill no)
			(layer "F.Fab")
		)
		(pad "A" smd rect
			(at 0 -1.143 180)
			(size 0.5588 1.016)
			(layers "F.Cu" "F.Mask" "F.Paste")
			(net "SW_HDD_R16")
		)
		(pad "K" smd rect
			(at 0 1.143 180)
			(size 0.5588 1.016)
			(layers "F.Cu" "F.Mask" "F.Paste")
			(net "SW_HDD_N16")
		)
	)
	(footprint ""
		(layer "F.Cu")
		(at 80.137 -214.249)
		(property "Reference" "R236"
			(at 0 0 0)
			(layer "F.SilkS")
			(hide yes)
			(effects
				(font
					(size 1.27 1.27)
				)
			)
		)
		(property "Value" "130R3F-GP"
			(at -0.0254 -2.5146 0)
			(unlocked yes)
			(layer "F.Fab")
			(hide yes)
			(effects
				(font
					(size 1.016 1.016)
					(thickness 0.1524)
				)
			)
		)
		(property "Device Type" "R603H22"
			(at -0.0254 -4.0386 0)
			(unlocked yes)
			(layer "F.Fab")
			(hide yes)
			(effects
				(font
					(size 1.016 1.016)
					(thickness 0.1524)
				)
			)
		)
		(duplicate_pad_numbers_are_jumpers no)
		(fp_line
			(start -0.4826 0)
			(end -0.2032 0)
			(stroke
				(width 0.2032)
				(type default)
			)
			(layer "F.SilkS")
		)
		(fp_line
			(start 0.2032 0)
			(end 0.4826 0)
			(stroke
				(width 0.2032)
				(type default)
			)
			(layer "F.SilkS")
		)
		(fp_rect
			(start -0.5842 1.3335)
			(end 0.5842 -1.3335)
			(stroke
				(width 0)
				(type default)
			)
			(fill no)
			(layer "F.CrtYd")
		)
		(fp_rect
			(start -0.5842 1.3335)
			(end 0.5842 -1.3335)
			(stroke
				(width 0)
				(type default)
			)
			(fill no)
			(layer "F.Fab")
		)
		(pad "1" smd custom
			(at 0 -0.762)
			(size 0.2159 0.2159)
			(layers "F.Cu" "F.Mask" "F.Paste")
			(net "P5V_B_1")
			(options
				(clearance outline)
				(anchor circle)
			)
			(primitives
				(gr_poly
					(pts
						(arc
							(start -0.3302 -0.4318)
							(mid -0.402042 -0.402042)
							(end -0.4318 -0.3302)
						)
						(arc
							(start -0.4318 0.3302)
							(mid -0.402042 0.402042)
							(end -0.3302 0.4318)
						)
						(arc
							(start 0.3302 0.4318)
							(mid 0.402042 0.402042)
							(end 0.4318 0.3302)
						)
						(arc
							(start 0.4318 -0.3302)
							(mid 0.402042 -0.402042)
							(end 0.3302 -0.4318)
						)
					)
					(width 0)
					(fill yes)
				)
			)
		)
		(pad "2" smd custom
			(at 0 0.762)
			(size 0.2159 0.2159)
			(layers "F.Cu" "F.Mask" "F.Paste")
			(net "FLT_HDD2")
			(options
				(clearance outline)
				(anchor circle)
			)
			(primitives
				(gr_poly
					(pts
						(arc
							(start -0.3302 -0.4318)
							(mid -0.402042 -0.402042)
							(end -0.4318 -0.3302)
						)
						(arc
							(start -0.4318 0.3302)
							(mid -0.402042 0.402042)
							(end -0.3302 0.4318)
						)
						(arc
							(start 0.3302 0.4318)
							(mid 0.402042 0.402042)
							(end 0.4318 0.3302)
						)
						(arc
							(start 0.4318 -0.3302)
							(mid 0.402042 -0.402042)
							(end 0.3302 -0.4318)
						)
					)
					(width 0)
					(fill yes)
				)
			)
		)
	)
	(footprint ""
		(layer "F.Cu")
		(at 300.199806 -93.999812)
		(property "Reference" ""
			(at 0 0 0)
			(layer "F.SilkS")
			(hide yes)
			(effects
				(font
					(size 1.27 1.27)
				)
			)
		)
		(property "Value" "*"
			(at -8.398764 -8.057642 0)
			(unlocked yes)
			(layer "F.Fab")
			(hide yes)
			(effects
				(font
					(size 1.016 1.016)
					(thickness 0.1524)
				)
			)
		)
		(duplicate_pad_numbers_are_jumpers no)
		(fp_poly
			(pts
				(arc
					(start 7.3152 0)
					(mid 0 7.3152)
					(end -7.3152 0)
				)
				(arc
					(start -7.3152 -5.9944)
					(mid 0 -13.3096)
					(end 7.3152 -5.9944)
				)
			)
			(stroke
				(width 0)
				(type default)
			)
			(fill no)
			(layer "B.CrtYd")
		)
		(fp_poly
			(pts
				(arc
					(start 7.3152 0)
					(mid 0 7.3152)
					(end -7.3152 0)
				)
				(arc
					(start -7.3152 -5.9944)
					(mid 0 -13.3096)
					(end 7.3152 -5.9944)
				)
			)
			(stroke
				(width 0)
				(type default)
			)
			(fill no)
			(layer "F.CrtYd")
		)
		(fp_poly
			(pts
				(arc
					(start 7.3152 0)
					(mid 0 7.3152)
					(end -7.3152 0)
				)
				(arc
					(start -7.3152 -5.9944)
					(mid 0 -13.3096)
					(end 7.3152 -5.9944)
				)
			)
			(stroke
				(width 0)
				(type default)
			)
			(fill no)
			(layer "B.Fab")
		)
		(fp_poly
			(pts
				(arc
					(start 7.3152 0)
					(mid 0 7.3152)
					(end -7.3152 0)
				)
				(arc
					(start -7.3152 -5.9944)
					(mid 0 -13.3096)
					(end 7.3152 -5.9944)
				)
			)
			(stroke
				(width 0)
				(type default)
			)
			(fill no)
			(layer "F.Fab")
		)
		(pad "1" thru_hole oval
			(at 0 0)
			(size 14.0208 20.0152)
			(drill 0.0254
				(offset 0 -2.9972)
			)
			(layers "*.Cu" "*.Mask")
			(remove_unused_layers no)
			(net "Net_17")
			(clearance -1.002284)
			(thermal_gap 0.1524)
			(padstack
				(mode front_inner_back)
				(layer "Inner"
					(shape custom)
					(size 2.928012 2.928012)
					(options
						(anchor circle)
					)
					(primitives
						(gr_poly
							(pts
								(arc
									(start 4.571746 -2.084324)
									(mid 0.000333 7.430372)
									(end -4.571492 -2.084324)
								)
								(arc
									(start -4.571492 -2.084324)
									(mid -3.570296 -3.611977)
									(end -2.875026 -5.30098)
								)
								(arc
									(start -2.875026 -5.30098)
									(mid 0.000217 -7.43089)
									(end 2.87528 -5.30098)
								)
								(arc
									(start 2.87528 -5.30098)
									(mid 3.570511 -3.611956)
									(end 4.571746 -2.084324)
								)
							)
							(width 0)
							(fill yes)
						)
					)
					(clearance 0.1524)
				)
				(layer "B.Cu"
					(shape oval)
					(size 14.0208 20.0152)
					(offset 0 -2.9972)
					(clearance -1.002284)
				)
			)
		)
		(zone
			(layers "F.Cu" "B.Cu" "In1.Cu" "In2.Cu" "In3.Cu" "In4.Cu" "In5.Cu" "In6.Cu")
			(hatch none 0.5)
			(connect_pads
				(clearance 0)
			)
			(min_thickness 0.25)
			(keepout
				(tracks not_allowed)
				(vias allowed)
				(pads allowed)
				(copperpour not_allowed)
				(footprints allowed)
			)
			(placement
				(enabled no)
				(sheetname "")
			)
			(fill
				(thermal_gap 0.5)
				(thermal_bridge_width 0.5)
				(island_removal_mode 0)
			)
			(polygon
				(pts
					(arc
						(start 293.189406 -99.994212)
						(mid 300.199806 -107.004612)
						(end 307.210206 -99.994212)
					)
					(arc
						(start 307.210206 -93.999812)
						(mid 300.199806 -86.989412)
						(end 293.189406 -93.999812)
					)
				)
			)
		)
	)
	(footprint ""
		(layer "F.Cu")
		(at 254.585978 -227.34905 -90)
		(property "Reference" "C28"
			(at 0 0 270)
			(layer "F.SilkS")
			(hide yes)
			(effects
				(font
					(size 1.27 1.27)
				)
			)
		)
		(property "Value" "SCD1U16V2KX-3GP"
			(at 1.1811 -2.7051 270)
			(unlocked yes)
			(layer "F.Fab")
			(hide yes)
			(effects
				(font
					(size 1.016 1.016)
					(thickness 0.1524)
				)
			)
		)
		(property "Device Type" "C402H22"
			(at 1.1811 -4.2291 270)
			(unlocked yes)
			(layer "F.Fab")
			(hide yes)
			(effects
				(font
					(size 1.016 1.016)
					(thickness 0.1524)
				)
			)
		)
		(duplicate_pad_numbers_are_jumpers no)
		(fp_rect
			(start -0.4318 0.9525)
			(end 0.4318 -0.9525)
			(stroke
				(width 0)
				(type default)
			)
			(fill no)
			(layer "F.CrtYd")
		)
		(fp_rect
			(start -0.4318 0.9525)
			(end 0.4318 -0.9525)
			(stroke
				(width 0)
				(type default)
			)
			(fill no)
			(layer "F.Fab")
		)
		(pad "1" smd custom
			(at 0 -0.4445 270)
			(size 0.1524 0.1524)
			(layers "F.Cu" "F.Mask" "F.Paste")
			(net "P5V_B_1_SENSE")
			(options
				(clearance outline)
				(anchor circle)
			)
			(primitives
				(gr_poly
					(pts
						(arc
							(start 0.3048 -0.2032)
							(mid 0.275042 -0.275042)
							(end 0.2032 -0.3048)
						)
						(arc
							(start -0.2032 -0.3048)
							(mid -0.275042 -0.275042)
							(end -0.3048 -0.2032)
						)
						(arc
							(start -0.3048 0.2032)
							(mid -0.275042 0.275042)
							(end -0.2032 0.3048)
						)
						(arc
							(start 0.2032 0.3048)
							(mid 0.275042 0.275042)
							(end 0.3048 0.2032)
						)
					)
					(width 0)
					(fill yes)
				)
			)
		)
		(pad "2" smd custom
			(at 0 0.4445 270)
			(size 0.1524 0.1524)
			(layers "F.Cu" "F.Mask" "F.Paste")
			(net "GND")
			(options
				(clearance outline)
				(anchor circle)
			)
			(primitives
				(gr_poly
					(pts
						(arc
							(start 0.3048 -0.2032)
							(mid 0.275042 -0.275042)
							(end 0.2032 -0.3048)
						)
						(arc
							(start -0.2032 -0.3048)
							(mid -0.275042 -0.275042)
							(end -0.3048 -0.2032)
						)
						(arc
							(start -0.3048 0.2032)
							(mid -0.275042 0.275042)
							(end -0.2032 0.3048)
						)
						(arc
							(start 0.2032 0.3048)
							(mid 0.275042 0.275042)
							(end 0.3048 0.2032)
						)
					)
					(width 0)
					(fill yes)
				)
			)
		)
	)
	(footprint ""
		(layer "F.Cu")
		(at 35.654996 -364.236 -90)
		(property "Reference" "R931"
			(at 0 0 270)
			(layer "F.SilkS")
			(hide yes)
			(effects
				(font
					(size 1.27 1.27)
				)
			)
		)
		(property "Value" "10KR2F-2-GP"
			(at 0.064008 -3.993896 270)
			(unlocked yes)
			(layer "F.Fab")
			(hide yes)
			(effects
				(font
					(size 1.016 1.016)
					(thickness 0.1524)
				)
			)
		)
		(property "Device Type" "R402H16"
			(at 0.064008 -5.517896 270)
			(unlocked yes)
			(layer "F.Fab")
			(hide yes)
			(effects
				(font
					(size 1.016 1.016)
					(thickness 0.1524)
				)
			)
		)
		(duplicate_pad_numbers_are_jumpers no)
		(fp_line
			(start -0.508 -0.9398)
			(end -0.508 0.9398)
			(stroke
				(width 0.1524)
				(type default)
			)
			(layer "F.SilkS")
		)
		(fp_line
			(start 0.508 -0.9398)
			(end -0.508 -0.9398)
			(stroke
				(width 0.1524)
				(type default)
			)
			(layer "F.SilkS")
		)
		(fp_rect
			(start -0.508 0.9398)
			(end 0.508 -0.9398)
			(stroke
				(width 0)
				(type default)
			)
			(fill no)
			(layer "F.CrtYd")
		)
		(fp_rect
			(start -0.508 0.9398)
			(end 0.508 -0.9398)
			(stroke
				(width 0)
				(type default)
			)
			(fill no)
			(layer "F.Fab")
		)
		(pad "1" smd custom
			(at 0 -0.4445 270)
			(size 0.1397 0.1397)
			(layers "F.Cu" "F.Mask" "F.Paste")
			(net "GND")
			(options
				(clearance outline)
				(anchor circle)
			)
			(primitives
				(gr_poly
					(pts
						(arc
							(start -0.1778 -0.2794)
							(mid -0.249642 -0.249642)
							(end -0.2794 -0.1778)
						)
						(arc
							(start -0.2794 0.1778)
							(mid -0.249642 0.249642)
							(end -0.1778 0.2794)
						)
						(arc
							(start 0.1778 0.2794)
							(mid 0.249642 0.249642)
							(end 0.2794 0.1778)
						)
						(arc
							(start 0.2794 -0.1778)
							(mid 0.249642 -0.249642)
							(end 0.1778 -0.2794)
						)
					)
					(width 0)
					(fill yes)
				)
			)
		)
		(pad "2" smd custom
			(at 0 0.4445 270)
			(size 0.1397 0.1397)
			(layers "F.Cu" "F.Mask" "F.Paste")
			(net "FANTACH_F0")
			(options
				(clearance outline)
				(anchor circle)
			)
			(primitives
				(gr_poly
					(pts
						(arc
							(start -0.1778 -0.2794)
							(mid -0.249642 -0.249642)
							(end -0.2794 -0.1778)
						)
						(arc
							(start -0.2794 0.1778)
							(mid -0.249642 0.249642)
							(end -0.1778 0.2794)
						)
						(arc
							(start 0.1778 0.2794)
							(mid 0.249642 0.249642)
							(end 0.2794 0.1778)
						)
						(arc
							(start 0.2794 -0.1778)
							(mid 0.249642 -0.249642)
							(end 0.1778 -0.2794)
						)
					)
					(width 0)
					(fill yes)
				)
			)
		)
	)
	(footprint ""
		(layer "F.Cu")
		(at 332.105 -131.318 -90)
		(property "Reference" "Q83"
			(at 0 0 270)
			(layer "F.SilkS")
			(hide yes)
			(effects
				(font
					(size 1.27 1.27)
				)
			)
		)
		(property "Value" "2N7002KDW-GP"
			(at -2.3622 -8.2042 270)
			(unlocked yes)
			(layer "F.Fab")
			(hide yes)
			(effects
				(font
					(size 1.016 1.016)
					(thickness 0.1524)
				)
			)
		)
		(property "Device Type" "SOT-363H44"
			(at -2.3622 -10.1092 270)
			(unlocked yes)
			(layer "F.Fab")
			(hide yes)
			(effects
				(font
					(size 1.016 1.016)
					(thickness 0.1524)
				)
			)
		)
		(duplicate_pad_numbers_are_jumpers no)
		(fp_line
			(start -1.4478 1.7018)
			(end 1.4478 1.7018)
			(stroke
				(width 0.1524)
				(type default)
			)
			(layer "F.SilkS")
		)
		(fp_line
			(start 1.4478 1.7018)
			(end 1.4478 -1.7018)
			(stroke
				(width 0.1524)
				(type default)
			)
			(layer "F.SilkS")
		)
		(fp_line
			(start -1.27 1.524)
			(end -1.27 0.6604)
			(stroke
				(width 0.4826)
				(type default)
			)
			(layer "F.SilkS")
		)
		(fp_line
			(start -1.4478 -1.7018)
			(end -1.4478 1.7018)
			(stroke
				(width 0.1524)
				(type default)
			)
			(layer "F.SilkS")
		)
		(fp_line
			(start 1.4478 -1.7018)
			(end -1.4478 -1.7018)
			(stroke
				(width 0.1524)
				(type default)
			)
			(layer "F.SilkS")
		)
		(fp_poly
			(pts
				(xy -1.524 -1.778) (xy 1.524 -1.778) (xy 1.524 1.778) (xy -1.524 1.778)
			)
			(stroke
				(width 0)
				(type default)
			)
			(fill no)
			(layer "F.CrtYd")
		)
		(fp_poly
			(pts
				(xy -1.524 -1.778) (xy 1.524 -1.778) (xy 1.524 1.778) (xy -1.524 1.778)
			)
			(stroke
				(width 0)
				(type default)
			)
			(fill no)
			(layer "F.Fab")
		)
		(pad "1" smd rect
			(at -0.65024 0.9398 270)
			(size 0.4064 1.016)
			(layers "F.Cu" "F.Mask" "F.Paste")
			(net "GND")
		)
		(pad "2" smd rect
			(at 0 0.9398 270)
			(size 0.4064 1.016)
			(layers "F.Cu" "F.Mask" "F.Paste")
			(net "SW_PWR_R_HDD18")
		)
		(pad "3" smd rect
			(at 0.65024 0.9398 270)
			(size 0.4064 1.016)
			(layers "F.Cu" "F.Mask" "F.Paste")
			(net "SW_HDD_P18")
		)
		(pad "4" smd rect
			(at 0.65024 -0.9398 270)
			(size 0.4064 1.016)
			(layers "F.Cu" "F.Mask" "F.Paste")
			(net "GND")
		)
		(pad "5" smd rect
			(at 0 -0.9398 270)
			(size 0.4064 1.016)
			(layers "F.Cu" "F.Mask" "F.Paste")
			(net "SW_HDD_G18")
		)
		(pad "6" smd rect
			(at -0.65024 -0.9398 270)
			(size 0.4064 1.016)
			(layers "F.Cu" "F.Mask" "F.Paste")
			(net "SW_HDD_R18")
		)
	)
	(footprint ""
		(layer "F.Cu")
		(at 209.804 -227.965 -90)
		(property "Reference" "R20"
			(at 0 0 270)
			(layer "F.SilkS")
			(hide yes)
			(effects
				(font
					(size 1.27 1.27)
				)
			)
		)
		(property "Value" "4K7R2F-GP"
			(at 0.064008 -3.993896 270)
			(unlocked yes)
			(layer "F.Fab")
			(hide yes)
			(effects
				(font
					(size 1.016 1.016)
					(thickness 0.1524)
				)
			)
		)
		(property "Device Type" "R402H16"
			(at 0.064008 -5.517896 270)
			(unlocked yes)
			(layer "F.Fab")
			(hide yes)
			(effects
				(font
					(size 1.016 1.016)
					(thickness 0.1524)
				)
			)
		)
		(duplicate_pad_numbers_are_jumpers no)
		(fp_line
			(start -0.508 -0.9398)
			(end -0.508 0.9398)
			(stroke
				(width 0.1524)
				(type default)
			)
			(layer "F.SilkS")
		)
		(fp_line
			(start 0.508 -0.9398)
			(end -0.508 -0.9398)
			(stroke
				(width 0.1524)
				(type default)
			)
			(layer "F.SilkS")
		)
		(fp_rect
			(start -0.508 0.9398)
			(end 0.508 -0.9398)
			(stroke
				(width 0)
				(type default)
			)
			(fill no)
			(layer "F.CrtYd")
		)
		(fp_rect
			(start -0.508 0.9398)
			(end 0.508 -0.9398)
			(stroke
				(width 0)
				(type default)
			)
			(fill no)
			(layer "F.Fab")
		)
		(pad "1" smd custom
			(at 0 -0.4445 270)
			(size 0.1397 0.1397)
			(layers "F.Cu" "F.Mask" "F.Paste")
			(net "IO_EXP1_HDD_FAULT_INT_N")
			(options
				(clearance outline)
				(anchor circle)
			)
			(primitives
				(gr_poly
					(pts
						(arc
							(start -0.1778 -0.2794)
							(mid -0.249642 -0.249642)
							(end -0.2794 -0.1778)
						)
						(arc
							(start -0.2794 0.1778)
							(mid -0.249642 0.249642)
							(end -0.1778 0.2794)
						)
						(arc
							(start 0.1778 0.2794)
							(mid 0.249642 0.249642)
							(end 0.2794 0.1778)
						)
						(arc
							(start 0.2794 -0.1778)
							(mid 0.249642 -0.249642)
							(end 0.1778 -0.2794)
						)
					)
					(width 0)
					(fill yes)
				)
			)
		)
		(pad "2" smd custom
			(at 0 0.4445 270)
			(size 0.1397 0.1397)
			(layers "F.Cu" "F.Mask" "F.Paste")
			(net "P3V3_STBY_B")
			(options
				(clearance outline)
				(anchor circle)
			)
			(primitives
				(gr_poly
					(pts
						(arc
							(start -0.1778 -0.2794)
							(mid -0.249642 -0.249642)
							(end -0.2794 -0.1778)
						)
						(arc
							(start -0.2794 0.1778)
							(mid -0.249642 0.249642)
							(end -0.1778 0.2794)
						)
						(arc
							(start 0.1778 0.2794)
							(mid 0.249642 0.249642)
							(end 0.2794 0.1778)
						)
						(arc
							(start 0.2794 -0.1778)
							(mid 0.249642 -0.249642)
							(end 0.1778 -0.2794)
						)
					)
					(width 0)
					(fill yes)
				)
			)
		)
	)
)
